# BASEBOARD_FAB2 (Tioga Pass) — schematic netlist excerpt (pin names and nets, part order shuffled) for the footprints in the layout excerpt that follows; sources: Cadence DE-HDL packaged netlist, KiCad conversion of Wiwynn_Tioga_Pass_MB.brd

T1P8  TPAD-DIFF-4P-GP  pkg DISCRET-GB3  page 256
  \1\  = L3_73OHM_6INCH_DP
  \2\  = L3_73OHM_6INCH_DN
  GND1  = GND
  GND2  = GND

C1F20  CAP  0.22UF 16V 10% X7R  pkg 0402  page 181 : A = P3E_CPU1_PE3_MP_C_TXN<0> ; B = P3E_CPU1_PE3_MP_TXN<0>

(kicad_pcb
	(version 20260206)
	(generator "pcbnew")
	(generator_version "10.0")
	(general
		(thickness 1.6)
		(legacy_teardrops no)
	)
	(paper "A4")
	(title_block
		(title "Wiwynn_Tioga_Pass_MB.brd")
		(comment 1 "Tioga Pass / footprints 1341-1342 of 4770")
	)
	(layers
		(0 "F.Cu" signal "TOP")
		(4 "In1.Cu" signal "L2GND")
		(6 "In2.Cu" signal "L3")
		(8 "In3.Cu" signal "L4GND")
		(10 "In4.Cu" signal "L5")
		(12 "In5.Cu" signal "L6GND")
		(14 "In6.Cu" signal "L7VCC")
		(16 "In7.Cu" signal "L8VCC")
		(18 "In8.Cu" signal "L9GND")
		(20 "In9.Cu" signal "L10")
		(22 "In10.Cu" signal "L11GND")
		(24 "In11.Cu" signal "L12")
		(26 "In12.Cu" signal "L13GND")
		(2 "B.Cu" signal "BOTTOM")
		(9 "F.Adhes" user "F.Adhesive")
		(11 "B.Adhes" user "B.Adhesive")
		(13 "F.Paste" user "Package Geometry/Pastemask Top")
		(15 "B.Paste" user "Package Geometry/Pastemask Bottom")
		(5 "F.SilkS" user "Ref Des/Silkscreen Top")
		(7 "B.SilkS" user "Ref Des/Silkscreen Bottom")
		(1 "F.Mask" user "Board Geometry/Soldermask Top")
		(3 "B.Mask" user "Board Geometry/Soldermask Bottom")
		(17 "Dwgs.User" user "User.Drawings")
		(19 "Cmts.User" user "User.Comments")
		(21 "Eco1.User" user "User.Eco1")
		(23 "Eco2.User" user "User.Eco2")
		(25 "Edge.Cuts" user "Board Geometry/Outline")
		(27 "Margin" user)
		(31 "F.CrtYd" user "Package Geometry/Place Bound Top")
		(29 "B.CrtYd" user "Package Geometry/Place Bound Bottom")
		(35 "F.Fab" user "Ref Des/Assembly Top")
		(33 "B.Fab" user "Ref Des/Assembly Bottom")
	)
	(footprint ""
		(layer "F.Cu")
		(at 122.490484 12.014454 -90)
		(property "Reference" "T1P8"
			(at 0 0 270)
			(layer "F.SilkS")
			(hide yes)
			(effects
				(font
					(size 1.27 1.27)
				)
			)
		)
		(property "Value" "*"
			(at -3.302 1.12395 270)
			(unlocked yes)
			(layer "F.Fab")
			(hide yes)
			(effects
				(font
					(size 0.889 0.889)
					(thickness 0.1524)
				)
			)
		)
		(property "Device Type" "TPAD-DIFF-4P-GP_DISCRET-GB3-TPA"
			(at -3.302 -0.40005 270)
			(unlocked yes)
			(layer "F.Fab")
			(hide yes)
			(effects
				(font
					(size 0.889 0.889)
					(thickness 0.1524)
				)
			)
		)
		(duplicate_pad_numbers_are_jumpers no)
		(fp_line
			(start -2.286 2.286)
			(end 2.286 2.286)
			(stroke
				(width 0.1524)
				(type default)
			)
			(layer "F.SilkS")
		)
		(fp_line
			(start 2.286 2.286)
			(end 2.286 -2.286)
			(stroke
				(width 0.1524)
				(type default)
			)
			(layer "F.SilkS")
		)
		(fp_line
			(start -2.286 -2.286)
			(end -2.286 2.286)
			(stroke
				(width 0.1524)
				(type default)
			)
			(layer "F.SilkS")
		)
		(fp_line
			(start 2.286 -2.286)
			(end -2.286 -2.286)
			(stroke
				(width 0.1524)
				(type default)
			)
			(layer "F.SilkS")
		)
		(fp_line
			(start -2.413 -2.413)
			(end -2.413 -1.143)
			(stroke
				(width 0.4064)
				(type default)
			)
			(layer "F.SilkS")
		)
		(fp_line
			(start -1.143 -2.413)
			(end -2.413 -2.413)
			(stroke
				(width 0.4064)
				(type default)
			)
			(layer "F.SilkS")
		)
		(fp_rect
			(start -2.54 2.54)
			(end 2.54 -2.54)
			(stroke
				(width 0)
				(type default)
			)
			(fill no)
			(layer "F.CrtYd")
		)
		(fp_rect
			(start -2.54 2.54)
			(end 2.54 -2.54)
			(stroke
				(width 0)
				(type default)
			)
			(fill no)
			(layer "F.Fab")
		)
		(pad "1" thru_hole circle
			(at -1.27 -1.27 270)
			(size 1.524 1.524)
			(drill 0.9144)
			(layers "*.Cu" "*.Mask")
			(remove_unused_layers no)
			(net "L3_73OHM_6INCH_DP")
			(clearance -0.0508)
			(thermal_gap 0.127)
			(padstack
				(mode front_inner_back)
				(layer "Inner"
					(shape circle)
					(size 1.1684 1.1684)
					(clearance 0.127)
				)
				(layer "B.Cu"
					(shape circle)
					(size 1.524 1.524)
					(clearance -0.0508)
				)
			)
		)
		(pad "2" thru_hole circle
			(at 1.27 -1.27 270)
			(size 1.524 1.524)
			(drill 0.9144)
			(layers "*.Cu" "*.Mask")
			(remove_unused_layers no)
			(net "L3_73OHM_6INCH_DN")
			(clearance -0.0508)
			(thermal_gap 0.127)
			(padstack
				(mode front_inner_back)
				(layer "Inner"
					(shape circle)
					(size 1.1684 1.1684)
					(clearance 0.127)
				)
				(layer "B.Cu"
					(shape circle)
					(size 1.524 1.524)
					(clearance -0.0508)
				)
			)
		)
		(pad "GND1" thru_hole rect
			(at -1.27 1.27 270)
			(size 1.524 1.524)
			(drill 0.9144)
			(layers "*.Cu" "*.Mask")
			(remove_unused_layers no)
			(net "GND")
			(clearance -0.0508)
			(thermal_gap 0.127)
			(padstack
				(mode front_inner_back)
				(layer "Inner"
					(shape circle)
					(size 1.1684 1.1684)
					(clearance 0.127)
				)
				(layer "B.Cu"
					(shape rect)
					(size 1.524 1.524)
					(clearance -0.0508)
				)
			)
		)
		(pad "GND2" thru_hole rect
			(at 1.27 1.27 270)
			(size 1.524 1.524)
			(drill 0.9144)
			(layers "*.Cu" "*.Mask")
			(remove_unused_layers no)
			(net "GND")
			(clearance -0.0508)
			(thermal_gap 0.127)
			(padstack
				(mode front_inner_back)
				(layer "Inner"
					(shape circle)
					(size 1.1684 1.1684)
					(clearance 0.127)
				)
				(layer "B.Cu"
					(shape rect)
					(size 1.524 1.524)
					(clearance -0.0508)
				)
			)
		)
	)
	(footprint ""
		(layer "F.Cu")
		(at 13.8938 -23.241 90)
		(property "Reference" "C1F20"
			(at 0 0 90)
			(layer "F.SilkS")
			(hide yes)
			(effects
				(font
					(size 1.27 1.27)
				)
			)
		)
		(property "Value" ""
			(at 0 0 90)
			(layer "F.Fab")
			(effects
				(font
					(size 1.27 1.27)
				)
			)
		)
		(duplicate_pad_numbers_are_jumpers no)
		(fp_rect
			(start -0.3048 -0.1016)
			(end 0.3048 0.9906)
			(stroke
				(width 0)
				(type default)
			)
			(fill no)
			(layer "F.CrtYd")
		)
		(fp_line
			(start 0.3048 -0.1016)
			(end -0.3048 -0.1016)
			(stroke
				(width 0.1)
				(type default)
			)
			(layer "F.Fab")
		)
		(fp_line
			(start -0.3048 -0.1016)
			(end -0.3048 0.9906)
			(stroke
				(width 0.1)
				(type default)
			)
			(layer "F.Fab")
		)
		(fp_line
			(start 0.3048 0.9906)
			(end 0.3048 -0.1016)
			(stroke
				(width 0.1)
				(type default)
			)
			(layer "F.Fab")
		)
		(fp_line
			(start -0.3048 0.9906)
			(end 0.3048 0.9906)
			(stroke
				(width 0.1)
				(type default)
			)
			(layer "F.Fab")
		)
		(pad "1" smd rect
			(at 0 0 90)
			(size 0.508 0.508)
			(layers "F.Cu" "F.Mask" "F.Paste")
			(net "P3E_CPU1_PE3_MP_C_TXN<0>")
		)
		(pad "2" smd rect
			(at 0 0.889 90)
			(size 0.508 0.508)
			(layers "F.Cu" "F.Mask" "F.Paste")
			(net "P3E_CPU1_PE3_MP_TXN<0>")
		)
		(zone
			(layer "F.Cu")
			(hatch none 0.5)
			(connect_pads
				(clearance 0)
			)
			(min_thickness 0.25)
			(keepout
				(tracks allowed)
				(vias not_allowed)
				(pads allowed)
				(copperpour not_allowed)
				(footprints allowed)
			)
			(placement
				(enabled no)
				(sheetname "")
			)
			(fill
				(thermal_gap 0.5)
				(thermal_bridge_width 0.5)
				(island_removal_mode 0)
			)
			(polygon
				(pts
					(xy 14.1478 -22.987) (xy 14.5288 -22.987) (xy 14.5288 -23.495) (xy 14.1478 -23.495)
				)
			)
		)
		(zone
			(layer "F.Cu")
			(hatch none 0.5)
			(connect_pads
				(clearance 0)
			)
			(min_thickness 0.25)
			(keepout
				(tracks not_allowed)
				(vias allowed)
				(pads allowed)
				(copperpour not_allowed)
				(footprints allowed)
			)
			(placement
				(enabled no)
				(sheetname "")
			)
			(fill
				(thermal_gap 0.5)
				(thermal_bridge_width 0.5)
				(island_removal_mode 0)
			)
			(polygon
				(pts
					(xy 14.1478 -22.987) (xy 14.5288 -22.987) (xy 14.5288 -23.495) (xy 14.1478 -23.495)
				)
			)
		)
	)
)
